(kicad_pcb
	(version 20260206)
	(generator "pcbnew")
	(generator_version "10.0")
	(general
		(thickness 1.6)
		(legacy_teardrops no)
	)
	(paper "A4")
	(title_block
		(title "v1-tray-backplane — T6M_tray_BP_c_1023_1120.brd")
		(comment 1 "Open CloudServer (Microsoft) / footprints 47-56 of 170")
	)
	(layers
		(0 "F.Cu" signal "TOP")
		(4 "In1.Cu" signal "GND")
		(6 "In2.Cu" signal "IN1")
		(8 "In3.Cu" signal "VCC")
		(10 "In4.Cu" signal "VCC1")
		(12 "In5.Cu" signal "IN2")
		(14 "In6.Cu" signal "GND1")
		(2 "B.Cu" signal "BOTTOM")
		(9 "F.Adhes" user "F.Adhesive")
		(11 "B.Adhes" user "B.Adhesive")
		(13 "F.Paste" user "Package Geometry/Pastemask Top")
		(15 "B.Paste" user "Package Geometry/Pastemask Bottom")
		(5 "F.SilkS" user "Ref Des/Silkscreen Top")
		(7 "B.SilkS" user "Ref Des/Silkscreen Bottom")
		(1 "F.Mask" user "Board Geometry/Soldermask Top")
		(3 "B.Mask" user "Board Geometry/Soldermask Bottom")
		(17 "Dwgs.User" user "User.Drawings")
		(19 "Cmts.User" user "User.Comments")
		(21 "Eco1.User" user "User.Eco1")
		(23 "Eco2.User" user "User.Eco2")
		(25 "Edge.Cuts" user "Board Geometry/Outline")
		(27 "Margin" user)
		(31 "F.CrtYd" user "Package Geometry/Place Bound Top")
		(29 "B.CrtYd" user "Package Geometry/Place Bound Bottom")
		(35 "F.Fab" user "Ref Des/Assembly Top")
		(33 "B.Fab" user "Ref Des/Assembly Bottom")
	)
	(footprint ""
		(layer "F.Cu")
		(at 30.977332 -19.7358 -90)
		(property "Reference" "R86"
			(at 0.9144 -4.729988 90)
			(unlocked yes)
			(layer "F.SilkS")
			(effects
				(font
					(size 0.7874 0.5842)
					(thickness 0.1524)
				)
				(justify left)
			)
		)
		(property "Value" ""
			(at 0 0 270)
			(layer "F.Fab")
			(effects
				(font
					(size 1.27 1.27)
				)
			)
		)
		(duplicate_pad_numbers_are_jumpers no)
		(fp_line
			(start -0.7874 0.4064)
			(end -0.7874 -0.4064)
			(stroke
				(width 0.1524)
				(type default)
			)
			(layer "F.SilkS")
		)
		(fp_line
			(start 0.7874 0.4064)
			(end -0.7874 0.4064)
			(stroke
				(width 0.1524)
				(type default)
			)
			(layer "F.SilkS")
		)
		(fp_line
			(start -0.7874 -0.4064)
			(end 0.7874 -0.4064)
			(stroke
				(width 0.1524)
				(type default)
			)
			(layer "F.SilkS")
		)
		(fp_line
			(start 0.7874 -0.4064)
			(end 0.7874 0.4064)
			(stroke
				(width 0.1524)
				(type default)
			)
			(layer "F.SilkS")
		)
		(fp_poly
			(pts
				(xy -0.508 0.2794) (xy -0.508 0.2286) (xy -0.635 0.2286) (xy -0.635 -0.254) (xy -0.5334 -0.254)
				(xy -0.5334 -0.2794) (xy 0.5334 -0.2794) (xy 0.5334 -0.254) (xy 0.635 -0.254) (xy 0.635 0.254) (xy 0.5334 0.254)
				(xy 0.5334 0.2794)
			)
			(stroke
				(width 0)
				(type default)
			)
			(fill no)
			(layer "F.CrtYd")
		)
		(pad "1" smd rect
			(at 0.40005 0 270)
			(size 0.4572 0.508)
			(layers "F.Cu" "F.Mask" "F.Paste")
			(net "N39391900")
		)
		(pad "2" smd rect
			(at -0.40005 0 270)
			(size 0.4572 0.508)
			(layers "F.Cu" "F.Mask" "F.Paste")
			(net "P12V")
		)
	)
	(footprint ""
		(layer "F.Cu")
		(at 130.146552 -21.143468)
		(property "Reference" "R66"
			(at -61.8236 5.140452 0)
			(unlocked yes)
			(layer "F.SilkS")
			(effects
				(font
					(size 0.7874 0.5842)
					(thickness 0.1524)
				)
				(justify left)
			)
		)
		(property "Value" ""
			(at 0 0 0)
			(layer "F.Fab")
			(effects
				(font
					(size 1.27 1.27)
				)
			)
		)
		(duplicate_pad_numbers_are_jumpers no)
		(fp_line
			(start -0.7874 -0.4064)
			(end 0.7874 -0.4064)
			(stroke
				(width 0.1524)
				(type default)
			)
			(layer "F.SilkS")
		)
		(fp_line
			(start -0.7874 0.4064)
			(end -0.7874 -0.4064)
			(stroke
				(width 0.1524)
				(type default)
			)
			(layer "F.SilkS")
		)
		(fp_line
			(start 0.7874 -0.4064)
			(end 0.7874 0.4064)
			(stroke
				(width 0.1524)
				(type default)
			)
			(layer "F.SilkS")
		)
		(fp_line
			(start 0.7874 0.4064)
			(end -0.7874 0.4064)
			(stroke
				(width 0.1524)
				(type default)
			)
			(layer "F.SilkS")
		)
		(fp_poly
			(pts
				(xy -0.508 0.2794) (xy -0.508 0.2286) (xy -0.635 0.2286) (xy -0.635 -0.254) (xy -0.5334 -0.254)
				(xy -0.5334 -0.2794) (xy 0.5334 -0.2794) (xy 0.5334 -0.254) (xy 0.635 -0.254) (xy 0.635 0.254) (xy 0.5334 0.254)
				(xy 0.5334 0.2794)
			)
			(stroke
				(width 0)
				(type default)
			)
			(fill no)
			(layer "F.CrtYd")
		)
		(pad "1" smd rect
			(at 0.40005 0)
			(size 0.4572 0.508)
			(layers "F.Cu" "F.Mask" "F.Paste")
			(net "ENET10G_1_MOD_DEF0")
		)
		(pad "2" smd rect
			(at -0.40005 0)
			(size 0.4572 0.508)
			(layers "F.Cu" "F.Mask" "F.Paste")
			(net "SFP1_PRESENT_N")
		)
	)
	(footprint ""
		(layer "F.Cu")
		(at 157.781752 -26.709878)
		(property "Reference" "R43"
			(at 33.5534 17.942052 0)
			(unlocked yes)
			(layer "F.SilkS")
			(effects
				(font
					(size 0.7874 0.5842)
					(thickness 0.1524)
				)
				(justify left)
			)
		)
		(property "Value" ""
			(at 0 0 0)
			(layer "F.Fab")
			(effects
				(font
					(size 1.27 1.27)
				)
			)
		)
		(duplicate_pad_numbers_are_jumpers no)
		(fp_line
			(start -0.7874 -0.4064)
			(end 0.7874 -0.4064)
			(stroke
				(width 0.1524)
				(type default)
			)
			(layer "F.SilkS")
		)
		(fp_line
			(start -0.7874 0.4064)
			(end -0.7874 -0.4064)
			(stroke
				(width 0.1524)
				(type default)
			)
			(layer "F.SilkS")
		)
		(fp_line
			(start 0.7874 -0.4064)
			(end 0.7874 0.4064)
			(stroke
				(width 0.1524)
				(type default)
			)
			(layer "F.SilkS")
		)
		(fp_line
			(start 0.7874 0.4064)
			(end -0.7874 0.4064)
			(stroke
				(width 0.1524)
				(type default)
			)
			(layer "F.SilkS")
		)
		(fp_poly
			(pts
				(xy -0.508 0.2794) (xy -0.508 0.2286) (xy -0.635 0.2286) (xy -0.635 -0.254) (xy -0.5334 -0.254)
				(xy -0.5334 -0.2794) (xy 0.5334 -0.2794) (xy 0.5334 -0.254) (xy 0.635 -0.254) (xy 0.635 0.254) (xy 0.5334 0.254)
				(xy 0.5334 0.2794)
			)
			(stroke
				(width 0)
				(type default)
			)
			(fill no)
			(layer "F.CrtYd")
		)
		(pad "1" smd rect
			(at 0.40005 0)
			(size 0.4572 0.508)
			(layers "F.Cu" "F.Mask" "F.Paste")
			(net "GND")
		)
		(pad "2" smd rect
			(at -0.40005 0)
			(size 0.4572 0.508)
			(layers "F.Cu" "F.Mask" "F.Paste")
			(net "ENET10G_1_RS1")
		)
	)
	(footprint ""
		(layer "F.Cu")
		(at 130.101848 -23.256494 180)
		(property "Reference" "R13"
			(at 61.778896 -5.14604 0)
			(unlocked yes)
			(layer "F.SilkS")
			(effects
				(font
					(size 0.7874 0.5842)
					(thickness 0.1524)
				)
				(justify left)
			)
		)
		(property "Value" ""
			(at 0 0 180)
			(layer "F.Fab")
			(effects
				(font
					(size 1.27 1.27)
				)
			)
		)
		(duplicate_pad_numbers_are_jumpers no)
		(fp_line
			(start 0.7874 0.4064)
			(end -0.7874 0.4064)
			(stroke
				(width 0.1524)
				(type default)
			)
			(layer "F.SilkS")
		)
		(fp_line
			(start 0.7874 -0.4064)
			(end 0.7874 0.4064)
			(stroke
				(width 0.1524)
				(type default)
			)
			(layer "F.SilkS")
		)
		(fp_line
			(start -0.7874 0.4064)
			(end -0.7874 -0.4064)
			(stroke
				(width 0.1524)
				(type default)
			)
			(layer "F.SilkS")
		)
		(fp_line
			(start -0.7874 -0.4064)
			(end 0.7874 -0.4064)
			(stroke
				(width 0.1524)
				(type default)
			)
			(layer "F.SilkS")
		)
		(fp_poly
			(pts
				(xy -0.508 0.2794) (xy -0.508 0.2286) (xy -0.635 0.2286) (xy -0.635 -0.254) (xy -0.5334 -0.254)
				(xy -0.5334 -0.2794) (xy 0.5334 -0.2794) (xy 0.5334 -0.254) (xy 0.635 -0.254) (xy 0.635 0.254) (xy 0.5334 0.254)
				(xy 0.5334 0.2794)
			)
			(stroke
				(width 0)
				(type default)
			)
			(fill no)
			(layer "F.CrtYd")
		)
		(pad "1" smd rect
			(at 0.40005 0 180)
			(size 0.4572 0.508)
			(layers "F.Cu" "F.Mask" "F.Paste")
			(net "P3V3_BLAD1")
		)
		(pad "2" smd rect
			(at -0.40005 0 180)
			(size 0.4572 0.508)
			(layers "F.Cu" "F.Mask" "F.Paste")
			(net "ENET10G_1_LOS")
		)
	)
	(footprint ""
		(layer "F.Cu")
		(at 376.121676 -38.7604)
		(property "Reference" "FS7"
			(at 35.262312 22.86508 0)
			(unlocked yes)
			(layer "F.SilkS")
			(effects
				(font
					(size 0.7874 0.5842)
					(thickness 0.1524)
				)
				(justify left)
			)
		)
		(property "Value" ""
			(at 0 0 0)
			(layer "F.Fab")
			(effects
				(font
					(size 1.27 1.27)
				)
			)
		)
		(duplicate_pad_numbers_are_jumpers no)
		(fp_line
			(start -0.650494 -1.050036)
			(end 3.550412 -1.050036)
			(stroke
				(width 0.1524)
				(type default)
			)
			(layer "F.SilkS")
		)
		(fp_line
			(start -0.650494 1.050036)
			(end -0.650494 -1.050036)
			(stroke
				(width 0.1524)
				(type default)
			)
			(layer "F.SilkS")
		)
		(fp_line
			(start 3.550412 -1.050036)
			(end 3.550412 1.050036)
			(stroke
				(width 0.1524)
				(type default)
			)
			(layer "F.SilkS")
		)
		(fp_line
			(start 3.550412 1.050036)
			(end -0.650494 1.050036)
			(stroke
				(width 0.1524)
				(type default)
			)
			(layer "F.SilkS")
		)
		(fp_poly
			(pts
				(xy 3.228086 -0.9652) (xy 3.228086 -1.100074) (xy -0.327914 -1.100074) (xy -0.327914 -0.9652) (xy -0.556514 -0.9652)
				(xy -0.556514 0.9652) (xy -0.327914 0.9652) (xy -0.327914 1.100074) (xy 3.228086 1.100074) (xy 3.228086 0.9652)
				(xy 3.456686 0.9652) (xy 3.456686 -0.9652)
			)
			(stroke
				(width 0)
				(type default)
			)
			(fill no)
			(layer "F.CrtYd")
		)
		(fp_text user "1"
			(at -1.225042 0.74168 0)
			(unlocked yes)
			(layer "F.SilkS")
			(effects
				(font
					(size 0.7874 0.5842)
					(thickness 0.1524)
				)
				(justify left)
			)
		)
		(fp_text user "2"
			(at 3.905758 0.20828 0)
			(unlocked yes)
			(layer "F.SilkS")
			(effects
				(font
					(size 0.7874 0.5842)
					(thickness 0.1524)
				)
				(justify left)
			)
		)
		(pad "1" smd rect
			(at 0 0)
			(size 1.016 1.8034)
			(layers "F.Cu" "F.Mask" "F.Paste")
			(net "P3V3_BLAD2")
		)
		(pad "2" smd rect
			(at 2.899918 0)
			(size 1.016 1.8034)
			(layers "F.Cu" "F.Mask" "F.Paste")
			(net "P3V3_10G_3_VCCR_L")
		)
	)
	(footprint ""
		(layer "F.Cu")
		(at 313.338464 -36.54933 180)
		(property "Reference" "FS6"
			(at 2.570988 6.850888 0)
			(unlocked yes)
			(layer "F.SilkS")
			(effects
				(font
					(size 0.7874 0.5842)
					(thickness 0.1524)
				)
				(justify left)
			)
		)
		(property "Value" ""
			(at 0 0 180)
			(layer "F.Fab")
			(effects
				(font
					(size 1.27 1.27)
				)
			)
		)
		(duplicate_pad_numbers_are_jumpers no)
		(fp_line
			(start 3.550412 1.050036)
			(end -0.650494 1.050036)
			(stroke
				(width 0.1524)
				(type default)
			)
			(layer "F.SilkS")
		)
		(fp_line
			(start 3.550412 -1.050036)
			(end 3.550412 1.050036)
			(stroke
				(width 0.1524)
				(type default)
			)
			(layer "F.SilkS")
		)
		(fp_line
			(start -0.650494 1.050036)
			(end -0.650494 -1.050036)
			(stroke
				(width 0.1524)
				(type default)
			)
			(layer "F.SilkS")
		)
		(fp_line
			(start -0.650494 -1.050036)
			(end 3.550412 -1.050036)
			(stroke
				(width 0.1524)
				(type default)
			)
			(layer "F.SilkS")
		)
		(fp_poly
			(pts
				(xy 3.228086 -0.9652) (xy 3.228086 -1.100074) (xy -0.327914 -1.100074) (xy -0.327914 -0.9652) (xy -0.556514 -0.9652)
				(xy -0.556514 0.9652) (xy -0.327914 0.9652) (xy -0.327914 1.100074) (xy 3.228086 1.100074) (xy 3.228086 0.9652)
				(xy 3.456686 0.9652) (xy 3.456686 -0.9652)
			)
			(stroke
				(width 0)
				(type default)
			)
			(fill no)
			(layer "F.CrtYd")
		)
		(fp_text user "2"
			(at 5.098542 0.323088 0)
			(unlocked yes)
			(layer "F.SilkS")
			(effects
				(font
					(size 0.7874 0.5842)
					(thickness 0.1524)
				)
				(justify left)
			)
		)
		(fp_text user "1"
			(at -0.565658 -0.819912 0)
			(unlocked yes)
			(layer "F.SilkS")
			(effects
				(font
					(size 0.7874 0.5842)
					(thickness 0.1524)
				)
				(justify left)
			)
		)
		(pad "1" smd rect
			(at 0 0 180)
			(size 1.016 1.8034)
			(layers "F.Cu" "F.Mask" "F.Paste")
			(net "P3V3_BLAD2")
		)
		(pad "2" smd rect
			(at 2.899918 0 180)
			(size 1.016 1.8034)
			(layers "F.Cu" "F.Mask" "F.Paste")
			(net "P3V3_10G_4_VCCT_L")
		)
	)
	(footprint ""
		(layer "F.Cu")
		(at 103.6828 -2.921 90)
		(property "Reference" "C23"
			(at -2.3622 -4.765548 90)
			(unlocked yes)
			(layer "F.SilkS")
			(effects
				(font
					(size 0.7874 0.5842)
					(thickness 0.1524)
				)
				(justify left)
			)
		)
		(property "Value" ""
			(at 0 0 90)
			(layer "F.Fab")
			(effects
				(font
					(size 1.27 1.27)
				)
			)
		)
		(duplicate_pad_numbers_are_jumpers no)
		(fp_line
			(start 0.7874 -0.4064)
			(end 0.7874 0.4064)
			(stroke
				(width 0.1524)
				(type default)
			)
			(layer "F.SilkS")
		)
		(fp_line
			(start -0.7874 -0.4064)
			(end 0.7874 -0.4064)
			(stroke
				(width 0.1524)
				(type default)
			)
			(layer "F.SilkS")
		)
		(fp_line
			(start 0 0.381)
			(end 0 -0.381)
			(stroke
				(width 0.1524)
				(type default)
			)
			(layer "F.SilkS")
		)
		(fp_line
			(start 0.7874 0.4064)
			(end -0.7874 0.4064)
			(stroke
				(width 0.1524)
				(type default)
			)
			(layer "F.SilkS")
		)
		(fp_line
			(start -0.7874 0.4064)
			(end -0.7874 -0.4064)
			(stroke
				(width 0.1524)
				(type default)
			)
			(layer "F.SilkS")
		)
		(fp_poly
			(pts
				(xy -0.5334 0.254) (xy -0.635 0.254) (xy -0.635 0.2286) (xy -0.635 -0.254) (xy -0.5334 -0.254) (xy -0.5334 -0.2794)
				(xy 0.5334 -0.2794) (xy 0.5334 -0.254) (xy 0.635 -0.254) (xy 0.635 0.254) (xy 0.5334 0.254) (xy 0.5334 0.2794)
				(xy -0.508 0.2794) (xy -0.5334 0.2794)
			)
			(stroke
				(width 0)
				(type default)
			)
			(fill no)
			(layer "F.CrtYd")
		)
		(pad "1" smd rect
			(at 0.40005 0 90)
			(size 0.4572 0.508)
			(layers "F.Cu" "F.Mask" "F.Paste")
			(net "P3V3_10G_2_VCCR")
		)
		(pad "2" smd rect
			(at -0.40005 0 90)
			(size 0.4572 0.508)
			(layers "F.Cu" "F.Mask" "F.Paste")
			(net "GND")
		)
	)
	(footprint ""
		(layer "F.Cu")
		(at 117.31244 -22.17801)
		(property "Reference" "R2"
			(at -61.341 5.115052 0)
			(unlocked yes)
			(layer "F.SilkS")
			(effects
				(font
					(size 0.7874 0.5842)
					(thickness 0.1524)
				)
				(justify left)
			)
		)
		(property "Value" ""
			(at 0 0 0)
			(layer "F.Fab")
			(effects
				(font
					(size 1.27 1.27)
				)
			)
		)
		(duplicate_pad_numbers_are_jumpers no)
		(fp_line
			(start -0.7874 -0.4064)
			(end 0.7874 -0.4064)
			(stroke
				(width 0.1524)
				(type default)
			)
			(layer "F.SilkS")
		)
		(fp_line
			(start -0.7874 0.4064)
			(end -0.7874 -0.4064)
			(stroke
				(width 0.1524)
				(type default)
			)
			(layer "F.SilkS")
		)
		(fp_line
			(start 0.7874 -0.4064)
			(end 0.7874 0.4064)
			(stroke
				(width 0.1524)
				(type default)
			)
			(layer "F.SilkS")
		)
		(fp_line
			(start 0.7874 0.4064)
			(end -0.7874 0.4064)
			(stroke
				(width 0.1524)
				(type default)
			)
			(layer "F.SilkS")
		)
		(fp_poly
			(pts
				(xy -0.508 0.2794) (xy -0.508 0.2286) (xy -0.635 0.2286) (xy -0.635 -0.254) (xy -0.5334 -0.254)
				(xy -0.5334 -0.2794) (xy 0.5334 -0.2794) (xy 0.5334 -0.254) (xy 0.635 -0.254) (xy 0.635 0.254) (xy 0.5334 0.254)
				(xy 0.5334 0.2794)
			)
			(stroke
				(width 0)
				(type default)
			)
			(fill no)
			(layer "F.CrtYd")
		)
		(pad "1" smd rect
			(at 0.40005 0)
			(size 0.4572 0.508)
			(layers "F.Cu" "F.Mask" "F.Paste")
			(net "P3V3_BLAD1")
		)
		(pad "2" smd rect
			(at -0.40005 0)
			(size 0.4572 0.508)
			(layers "F.Cu" "F.Mask" "F.Paste")
			(net "ENET10G_2_TX_FAULT")
		)
	)
	(footprint ""
		(layer "F.Cu")
		(at 155.091384 -40.288972)
		(property "Reference" "FS1"
			(at 35.25774 25.689052 0)
			(unlocked yes)
			(layer "F.SilkS")
			(effects
				(font
					(size 0.7874 0.5842)
					(thickness 0.1524)
				)
				(justify left)
			)
		)
		(property "Value" ""
			(at 0 0 0)
			(layer "F.Fab")
			(effects
				(font
					(size 1.27 1.27)
				)
			)
		)
		(duplicate_pad_numbers_are_jumpers no)
		(fp_line
			(start -0.650494 -1.050036)
			(end 3.550412 -1.050036)
			(stroke
				(width 0.1524)
				(type default)
			)
			(layer "F.SilkS")
		)
		(fp_line
			(start -0.650494 1.050036)
			(end -0.650494 -1.050036)
			(stroke
				(width 0.1524)
				(type default)
			)
			(layer "F.SilkS")
		)
		(fp_line
			(start 3.550412 -1.050036)
			(end 3.550412 1.050036)
			(stroke
				(width 0.1524)
				(type default)
			)
			(layer "F.SilkS")
		)
		(fp_line
			(start 3.550412 1.050036)
			(end -0.650494 1.050036)
			(stroke
				(width 0.1524)
				(type default)
			)
			(layer "F.SilkS")
		)
		(fp_poly
			(pts
				(xy 3.228086 -0.9652) (xy 3.228086 -1.100074) (xy -0.327914 -1.100074) (xy -0.327914 -0.9652) (xy -0.556514 -0.9652)
				(xy -0.556514 0.9652) (xy -0.327914 0.9652) (xy -0.327914 1.100074) (xy 3.228086 1.100074) (xy 3.228086 0.9652)
				(xy 3.456686 0.9652) (xy 3.456686 -0.9652)
			)
			(stroke
				(width 0)
				(type default)
			)
			(fill no)
			(layer "F.CrtYd")
		)
		(fp_text user "1"
			(at -1.051814 -1.615948 0)
			(unlocked yes)
			(layer "F.SilkS")
			(effects
				(font
					(size 0.7874 0.5842)
					(thickness 0.1524)
				)
				(justify left)
			)
		)
		(fp_text user "2"
			(at 2.986786 -1.793748 0)
			(unlocked yes)
			(layer "F.SilkS")
			(effects
				(font
					(size 0.7874 0.5842)
					(thickness 0.1524)
				)
				(justify left)
			)
		)
		(pad "1" smd rect
			(at 0 0)
			(size 1.016 1.8034)
			(layers "F.Cu" "F.Mask" "F.Paste")
			(net "P3V3_BLAD1")
		)
		(pad "2" smd rect
			(at 2.899918 0)
			(size 1.016 1.8034)
			(layers "F.Cu" "F.Mask" "F.Paste")
			(net "P3V3_10G_1_VCCT_L")
		)
	)
	(footprint ""
		(layer "F.Cu")
		(at 351.177352 -23.256494 180)
		(property "Reference" "R29"
			(at 58.908696 4.30276 0)
			(unlocked yes)
			(layer "F.SilkS")
			(effects
				(font
					(size 0.7874 0.5842)
					(thickness 0.1524)
				)
				(justify left)
			)
		)
		(property "Value" ""
			(at 0 0 180)
			(layer "F.Fab")
			(effects
				(font
					(size 1.27 1.27)
				)
			)
		)
		(duplicate_pad_numbers_are_jumpers no)
		(fp_line
			(start 0.7874 0.4064)
			(end -0.7874 0.4064)
			(stroke
				(width 0.1524)
				(type default)
			)
			(layer "F.SilkS")
		)
		(fp_line
			(start 0.7874 -0.4064)
			(end 0.7874 0.4064)
			(stroke
				(width 0.1524)
				(type default)
			)
			(layer "F.SilkS")
		)
		(fp_line
			(start -0.7874 0.4064)
			(end -0.7874 -0.4064)
			(stroke
				(width 0.1524)
				(type default)
			)
			(layer "F.SilkS")
		)
		(fp_line
			(start -0.7874 -0.4064)
			(end 0.7874 -0.4064)
			(stroke
				(width 0.1524)
				(type default)
			)
			(layer "F.SilkS")
		)
		(fp_poly
			(pts
				(xy -0.508 0.2794) (xy -0.508 0.2286) (xy -0.635 0.2286) (xy -0.635 -0.254) (xy -0.5334 -0.254)
				(xy -0.5334 -0.2794) (xy 0.5334 -0.2794) (xy 0.5334 -0.254) (xy 0.635 -0.254) (xy 0.635 0.254) (xy 0.5334 0.254)
				(xy 0.5334 0.2794)
			)
			(stroke
				(width 0)
				(type default)
			)
			(fill no)
			(layer "F.CrtYd")
		)
		(pad "1" smd rect
			(at 0.40005 0 180)
			(size 0.4572 0.508)
			(layers "F.Cu" "F.Mask" "F.Paste")
			(net "P3V3_BLAD2")
		)
		(pad "2" smd rect
			(at -0.40005 0 180)
			(size 0.4572 0.508)
			(layers "F.Cu" "F.Mask" "F.Paste")
			(net "ENET10G_3_LOS")
		)
	)
)
